(kicad_pcb
	(version 20241229)
	(generator "pcbnew")
	(generator_version "9.0")
	(general
		(thickness 1.711)
		(legacy_teardrops no)
	)
	(paper "A4")
	(title_block
		(title "Antmicro Baseboard for Jetson AGX Thor")
		(date "2026-02-18")
		(rev "1.1.0")
		(company "Antmicro Ltd")
		(comment 1 "www.antmicro.com")
		(comment 9 "footprints 815-818 of 1170")
	)
	(layers
		(0 "F.Cu" signal)
		(4 "In1.Cu" signal)
		(6 "In2.Cu" signal)
		(8 "In3.Cu" signal)
		(10 "In4.Cu" jumper)
		(12 "In5.Cu" signal)
		(14 "In6.Cu" signal)
		(16 "In7.Cu" signal)
		(18 "In8.Cu" signal)
		(2 "B.Cu" signal)
		(9 "F.Adhes" user "F.Adhesive")
		(11 "B.Adhes" user "B.Adhesive")
		(13 "F.Paste" user)
		(15 "B.Paste" user)
		(5 "F.SilkS" user "F.Silkscreen")
		(7 "B.SilkS" user "B.Silkscreen")
		(1 "F.Mask" user)
		(3 "B.Mask" user)
		(17 "Dwgs.User" user "User.Drawings")
		(19 "Cmts.User" user "User.Comments")
		(21 "Eco1.User" user "User.Eco1")
		(23 "Eco2.User" user "User.Eco2")
		(25 "Edge.Cuts" user)
		(27 "Margin" user)
		(31 "F.CrtYd" user "F.Courtyard")
		(29 "B.CrtYd" user "B.Courtyard")
		(35 "F.Fab" user)
		(33 "B.Fab" user)
	)
	(footprint "antmicro-footprints:R_0402_1005Metric"
		(layer "B.Cu")
		(at 200.8 128.2 180)
		(descr "Resistor SMD 0402")
		(tags "resistor SMD 0402")
		(property "Reference" "R194"
			(at -3.8 -0.4 0)
			(layer "B.SilkS")
			(effects
				(font
					(size 0.7 0.7)
					(thickness 0.15)
				)
				(justify left bottom mirror)
			)
		)
		(property "Value" "R_100k_0402"
			(at -1.011843 -1.772046 0)
			(layer "B.Fab")
			(effects
				(font
					(size 0.7 0.7)
					(thickness 0.15)
				)
				(justify left bottom mirror)
			)
		)
		(property "Datasheet" "https://www.bourns.com/docs/product-datasheets/cr.pdf"
			(at 0 0 0)
			(layer "B.Fab")
			(hide yes)
			(effects
				(font
					(size 1.27 1.27)
					(thickness 0.15)
				)
				(justify mirror)
			)
		)
		(property "Description" "SMD Chip Resistor, 100 kohm, ± 1%, 62.5 mW, 0402 [1005 Metric], Thick Film, General Purpose"
			(at 0 0 0)
			(layer "B.Fab")
			(hide yes)
			(effects
				(font
					(size 1.27 1.27)
					(thickness 0.15)
				)
				(justify mirror)
			)
		)
		(property "MPN" "CR0402-FX-1003GLF"
			(at 0 0 0)
			(unlocked yes)
			(layer "B.Fab")
			(hide yes)
			(effects
				(font
					(size 1 1)
					(thickness 0.15)
				)
				(justify mirror)
			)
		)
		(property "Manufacturer" "Bourns"
			(at 0 0 0)
			(unlocked yes)
			(layer "B.Fab")
			(hide yes)
			(effects
				(font
					(size 1 1)
					(thickness 0.15)
				)
				(justify mirror)
			)
		)
		(property "License" "Apache-2.0"
			(at 0 0 0)
			(unlocked yes)
			(layer "B.Fab")
			(hide yes)
			(effects
				(font
					(size 1 1)
					(thickness 0.15)
				)
				(justify mirror)
			)
		)
		(property "Author" "Antmicro"
			(at 0 0 0)
			(unlocked yes)
			(layer "B.Fab")
			(hide yes)
			(effects
				(font
					(size 1 1)
					(thickness 0.15)
				)
				(justify mirror)
			)
		)
		(property "Val" "100k"
			(at 0 0 0)
			(unlocked yes)
			(layer "B.Fab")
			(hide yes)
			(effects
				(font
					(size 1 1)
					(thickness 0.15)
				)
				(justify mirror)
			)
		)
		(property "Tolerance" "1%"
			(at 0 0 0)
			(unlocked yes)
			(layer "B.Fab")
			(hide yes)
			(effects
				(font
					(size 1 1)
					(thickness 0.15)
				)
				(justify mirror)
			)
		)
		(sheetname "/USB Hub/")
		(sheetfile "usb_hub.kicad_sch")
		(attr smd)
		(fp_poly
			(pts
				(xy -0.925 0.47) (xy -0.925 -0.47) (xy 0.925 -0.47) (xy 0.925 0.47)
			)
			(stroke
				(width 0.05)
				(type default)
			)
			(fill no)
			(layer "B.CrtYd")
		)
		(fp_poly
			(pts
				(xy -0.5 0.25) (xy -0.5 -0.25) (xy 0.5 -0.25) (xy 0.5 0.25)
			)
			(stroke
				(width 0.15)
				(type solid)
			)
			(fill no)
			(layer "B.Fab")
		)
		(fp_text user "License: Apache-2.0"
			(at -0.949999 -5.169 0)
			(layer "B.Fab")
			(effects
				(font
					(size 0.7 0.7)
					(thickness 0.15)
				)
				(justify left bottom mirror)
			)
		)
		(fp_text user "${REFERENCE}"
			(at -0.95 -3.168 0)
			(layer "B.Fab")
			(effects
				(font
					(size 0.7 0.7)
					(thickness 0.15)
				)
				(justify left bottom mirror)
			)
		)
		(fp_text user "Author: Antmicro"
			(at -0.95 -4.169 0)
			(layer "B.Fab")
			(effects
				(font
					(size 0.7 0.7)
					(thickness 0.15)
				)
				(justify left bottom mirror)
			)
		)
		(pad "1" smd roundrect
			(at -0.48 0 180)
			(size 0.59 0.64)
			(layers "B.Cu" "B.Mask" "B.Paste")
			(roundrect_rratio 0.25)
			(net 1 "GND")
			(pintype "passive")
		)
		(pad "2" smd roundrect
			(at 0.48 0 180)
			(size 0.59 0.64)
			(layers "B.Cu" "B.Mask" "B.Paste")
			(roundrect_rratio 0.25)
			(net 924 "/USB Hub/HUB_SPI_D3")
			(pintype "passive")
		)
	)
	(footprint "antmicro-footprints:C_0805_2012Metric"
		(layer "B.Cu")
		(at 212.12 73.51 180)
		(descr "Capacitor SMD 0805")
		(tags "capacitor SMD 0805")
		(property "Reference" "C123"
			(at 2.02 -0.49 0)
			(layer "B.SilkS")
			(effects
				(font
					(size 0.7 0.7)
					(thickness 0.15)
				)
				(justify left bottom mirror)
			)
		)
		(property "Value" "C_22u_25V_0805"
			(at -2.055717 -1.963152 0)
			(layer "B.Fab")
			(effects
				(font
					(size 0.7 0.7)
					(thickness 0.15)
				)
				(justify left bottom mirror)
			)
		)
		(property "Datasheet" "https://product.samsungsem.com/mlcc/CL21A226MAYNNN.do"
			(at 0 0 0)
			(layer "B.Fab")
			(hide yes)
			(effects
				(font
					(size 1.27 1.27)
					(thickness 0.15)
				)
				(justify mirror)
			)
		)
		(property "Description" "SMT Multilayer Ceramic Capacitor, 22uF, +/-20%, 25V, X5R, 0805 [2012 Metric]"
			(at 0 0 0)
			(layer "B.Fab")
			(hide yes)
			(effects
				(font
					(size 1.27 1.27)
					(thickness 0.15)
				)
				(justify mirror)
			)
		)
		(property "Manufacturer" "Samsung Electro-Mechanics"
			(at 0 0 180)
			(unlocked yes)
			(layer "B.Fab")
			(hide yes)
			(effects
				(font
					(size 1 1)
					(thickness 0.15)
				)
				(justify mirror)
			)
		)
		(property "MPN" "CL21A226MAYNNNE"
			(at 0 0 180)
			(unlocked yes)
			(layer "B.Fab")
			(hide yes)
			(effects
				(font
					(size 1 1)
					(thickness 0.15)
				)
				(justify mirror)
			)
		)
		(property "Val" "22u"
			(at 0 0 180)
			(unlocked yes)
			(layer "B.Fab")
			(hide yes)
			(effects
				(font
					(size 1 1)
					(thickness 0.15)
				)
				(justify mirror)
			)
		)
		(property "License" "Apache-2.0"
			(at 0 0 180)
			(unlocked yes)
			(layer "B.Fab")
			(hide yes)
			(effects
				(font
					(size 1 1)
					(thickness 0.15)
				)
				(justify mirror)
			)
		)
		(property "Author" "Antmicro"
			(at 0 0 180)
			(unlocked yes)
			(layer "B.Fab")
			(hide yes)
			(effects
				(font
					(size 1 1)
					(thickness 0.15)
				)
				(justify mirror)
			)
		)
		(property "Voltage" "25V"
			(at 0 0 180)
			(unlocked yes)
			(layer "B.Fab")
			(hide yes)
			(effects
				(font
					(size 1 1)
					(thickness 0.15)
				)
				(justify mirror)
			)
		)
		(property "Dielectric" "X5R"
			(at 0 0 180)
			(unlocked yes)
			(layer "B.Fab")
			(hide yes)
			(effects
				(font
					(size 1 1)
					(thickness 0.15)
				)
				(justify mirror)
			)
		)
		(property "Public" "False"
			(at 0 0 180)
			(unlocked yes)
			(layer "B.Fab")
			(hide yes)
			(effects
				(font
					(size 1 1)
					(thickness 0.15)
				)
				(justify mirror)
			)
		)
		(sheetname "/USB Debug, PD/")
		(sheetfile "usb_debug_pd.kicad_sch")
		(attr smd)
		(fp_line
			(start -0.3 0.7)
			(end 0.3 0.7)
			(stroke
				(width 0.15)
				(type solid)
			)
			(layer "B.SilkS")
		)
		(fp_line
			(start -0.3 -0.7)
			(end 0.3 -0.7)
			(stroke
				(width 0.15)
				(type solid)
			)
			(layer "B.SilkS")
		)
		(fp_rect
			(start 1.95 0.9)
			(end -1.95 -0.9)
			(stroke
				(width 0.05)
				(type default)
			)
			(fill no)
			(layer "B.CrtYd")
		)
		(fp_rect
			(start -0.95 0.675)
			(end 0.95 -0.675)
			(stroke
				(width 0.15)
				(type solid)
			)
			(fill no)
			(layer "B.Fab")
		)
		(fp_text user "${REFERENCE}"
			(at -1.9 -3.947 0)
			(layer "B.Fab")
			(effects
				(font
					(size 0.7 0.7)
					(thickness 0.15)
				)
				(justify left bottom mirror)
			)
		)
		(fp_text user "License: Apache-2.0"
			(at -1.9 -4.947 0)
			(layer "B.Fab")
			(effects
				(font
					(size 0.7 0.7)
					(thickness 0.15)
				)
				(justify left bottom mirror)
			)
		)
		(fp_text user "Author: Antmicro"
			(at -1.9 -5.947 0)
			(layer "B.Fab")
			(effects
				(font
					(size 0.7 0.7)
					(thickness 0.15)
				)
				(justify left bottom mirror)
			)
		)
		(pad "1" smd roundrect
			(at -1.1 0 180)
			(size 1.2 1.3)
			(layers "B.Cu" "B.Mask" "B.Paste")
			(roundrect_rratio 0.25)
			(net 176 "/USB Debug, PD/USBC0_VBUS")
			(pintype "passive")
		)
		(pad "2" smd roundrect
			(at 1.1 0 180)
			(size 1.2 1.3)
			(layers "B.Cu" "B.Mask" "B.Paste")
			(roundrect_rratio 0.25)
			(net 1 "GND")
			(pintype "passive")
		)
	)
	(footprint "antmicro-footprints:C_0402_1005Metric"
		(layer "B.Cu")
		(at 132 146 -90)
		(descr "Capacitor SMD 0402")
		(tags "capacitor SMD 0402")
		(property "Reference" "C205"
			(at -1.710532 -1.32 90)
			(layer "B.SilkS")
			(effects
				(font
					(size 0.7 0.7)
					(thickness 0.15)
				)
				(justify left bottom mirror)
			)
		)
		(property "Value" "C_100n_0402"
			(at -1.022927 -2.155213 90)
			(layer "B.Fab")
			(effects
				(font
					(size 0.7 0.7)
					(thickness 0.15)
				)
				(justify left bottom mirror)
			)
		)
		(property "Datasheet" "https://www.murata.com/products/productdetail?partno=GRM155R61H104KE14%23"
			(at 0 0 90)
			(layer "B.Fab")
			(hide yes)
			(effects
				(font
					(size 1.27 1.27)
					(thickness 0.15)
				)
				(justify mirror)
			)
		)
		(property "Description" "SMD Multilayer Ceramic Capacitor, 0.1 µF, 50 V, 0402 [1005 Metric], ± 10%, X5R, GRM Series"
			(at 0 0 90)
			(layer "B.Fab")
			(hide yes)
			(effects
				(font
					(size 1.27 1.27)
					(thickness 0.15)
				)
				(justify mirror)
			)
		)
		(property "MPN" "GRM155R61H104KE14D"
			(at 0 0 90)
			(unlocked yes)
			(layer "B.Fab")
			(hide yes)
			(effects
				(font
					(size 1 1)
					(thickness 0.15)
				)
				(justify mirror)
			)
		)
		(property "Val" "100n"
			(at 0 0 90)
			(unlocked yes)
			(layer "B.Fab")
			(hide yes)
			(effects
				(font
					(size 1 1)
					(thickness 0.15)
				)
				(justify mirror)
			)
		)
		(property "Voltage" "50V"
			(at 0 0 90)
			(unlocked yes)
			(layer "B.Fab")
			(hide yes)
			(effects
				(font
					(size 1 1)
					(thickness 0.15)
				)
				(justify mirror)
			)
		)
		(property "Dielectric" "X5R"
			(at 0 0 90)
			(unlocked yes)
			(layer "B.Fab")
			(hide yes)
			(effects
				(font
					(size 1 1)
					(thickness 0.15)
				)
				(justify mirror)
			)
		)
		(property "Manufacturer" "Murata"
			(at 0 0 90)
			(unlocked yes)
			(layer "B.Fab")
			(hide yes)
			(effects
				(font
					(size 1 1)
					(thickness 0.15)
				)
				(justify mirror)
			)
		)
		(property "License" "Apache-2.0"
			(at 0 0 90)
			(unlocked yes)
			(layer "B.Fab")
			(hide yes)
			(effects
				(font
					(size 1 1)
					(thickness 0.15)
				)
				(justify mirror)
			)
		)
		(property "Author" "Antmicro"
			(at 0 0 90)
			(unlocked yes)
			(layer "B.Fab")
			(hide yes)
			(effects
				(font
					(size 1 1)
					(thickness 0.15)
				)
				(justify mirror)
			)
		)
		(sheetname "/Peripherals/")
		(sheetfile "peripherals.kicad_sch")
		(attr smd)
		(fp_poly
			(pts
				(xy -0.925 0.47) (xy 0.925 0.47) (xy 0.925 -0.47) (xy -0.925 -0.47)
			)
			(stroke
				(width 0.05)
				(type default)
			)
			(fill no)
			(layer "B.CrtYd")
		)
		(fp_line
			(start -0.494 0.25)
			(end 0.504 0.25)
			(stroke
				(width 0.15)
				(type solid)
			)
			(layer "B.Fab")
		)
		(fp_line
			(start 0.504 0.25)
			(end 0.504 -0.248)
			(stroke
				(width 0.15)
				(type solid)
			)
			(layer "B.Fab")
		)
		(fp_line
			(start -0.494 -0.248)
			(end -0.494 0.25)
			(stroke
				(width 0.15)
				(type solid)
			)
			(layer "B.Fab")
		)
		(fp_line
			(start 0.504 -0.248)
			(end -0.494 -0.248)
			(stroke
				(width 0.15)
				(type solid)
			)
			(layer "B.Fab")
		)
		(fp_text user "${REFERENCE}"
			(at -0.939 -4.599 90)
			(layer "B.Fab")
			(effects
				(font
					(size 0.7 0.7)
					(thickness 0.15)
				)
				(justify left bottom mirror)
			)
		)
		(fp_text user "License: Apache-2.0"
			(at -0.939 -5.799 90)
			(layer "B.Fab")
			(effects
				(font
					(size 0.7 0.7)
					(thickness 0.15)
				)
				(justify left bottom mirror)
			)
		)
		(fp_text user "Author: Antmicro"
			(at -0.939 -3.399 90)
			(layer "B.Fab")
			(effects
				(font
					(size 0.7 0.7)
					(thickness 0.15)
				)
				(justify left bottom mirror)
			)
		)
		(pad "1" smd roundrect
			(at -0.48 0 270)
			(size 0.59 0.64)
			(layers "B.Cu" "B.Mask" "B.Paste")
			(roundrect_rratio 0.25)
			(net 1 "GND")
			(pintype "passive")
		)
		(pad "2" smd roundrect
			(at 0.48 0 270)
			(size 0.59 0.64)
			(layers "B.Cu" "B.Mask" "B.Paste")
			(roundrect_rratio 0.25)
			(net 2 "+3V3")
			(pintype "passive")
		)
	)
	(footprint "antmicro-footprints:R_0402_1005Metric"
		(layer "B.Cu")
		(at 235.8 122 180)
		(descr "Resistor SMD 0402")
		(tags "resistor SMD 0402")
		(property "Reference" "R73"
			(at -3.149999 -0.422 0)
			(layer "B.SilkS")
			(effects
				(font
					(size 0.7 0.7)
					(thickness 0.15)
				)
				(justify left bottom mirror)
			)
		)
		(property "Value" "R_2k2_0402"
			(at -1.011843 -1.772046 0)
			(layer "B.Fab")
			(effects
				(font
					(size 0.7 0.7)
					(thickness 0.15)
				)
				(justify left bottom mirror)
			)
		)
		(property "Datasheet" "https://www.bourns.com/docs/product-datasheets/cr.pdf"
			(at 0 0 0)
			(layer "B.Fab")
			(hide yes)
			(effects
				(font
					(size 1.27 1.27)
					(thickness 0.15)
				)
				(justify mirror)
			)
		)
		(property "Description" "SMD Chip Resistor, 2.2 kohm, ± 1%, 62.5 mW, 0402 [1005 Metric], Thick Film, General Purpose"
			(at 0 0 0)
			(layer "B.Fab")
			(hide yes)
			(effects
				(font
					(size 1.27 1.27)
					(thickness 0.15)
				)
				(justify mirror)
			)
		)
		(property "Manufacturer" "Bourns"
			(at 0 0 0)
			(unlocked yes)
			(layer "B.Fab")
			(hide yes)
			(effects
				(font
					(size 1 1)
					(thickness 0.15)
				)
				(justify mirror)
			)
		)
		(property "MPN" "CR0402-FX-2201GLF"
			(at 0 0 0)
			(unlocked yes)
			(layer "B.Fab")
			(hide yes)
			(effects
				(font
					(size 1 1)
					(thickness 0.15)
				)
				(justify mirror)
			)
		)
		(property "Val" "2k2"
			(at 0 0 0)
			(unlocked yes)
			(layer "B.Fab")
			(hide yes)
			(effects
				(font
					(size 1 1)
					(thickness 0.15)
				)
				(justify mirror)
			)
		)
		(property "License" "Apache-2.0"
			(at 0 0 0)
			(unlocked yes)
			(layer "B.Fab")
			(hide yes)
			(effects
				(font
					(size 1 1)
					(thickness 0.15)
				)
				(justify mirror)
			)
		)
		(property "Author" "Antmicro"
			(at 0 0 0)
			(unlocked yes)
			(layer "B.Fab")
			(hide yes)
			(effects
				(font
					(size 1 1)
					(thickness 0.15)
				)
				(justify mirror)
			)
		)
		(property "Tolerance" "1%"
			(at 0 0 0)
			(unlocked yes)
			(layer "B.Fab")
			(hide yes)
			(effects
				(font
					(size 1 1)
					(thickness 0.15)
				)
				(justify mirror)
			)
		)
		(sheetname "/USB Hub/")
		(sheetfile "usb_hub.kicad_sch")
		(attr smd)
		(fp_poly
			(pts
				(xy -0.925 0.47) (xy -0.925 -0.47) (xy 0.925 -0.47) (xy 0.925 0.47)
			)
			(stroke
				(width 0.05)
				(type default)
			)
			(fill no)
			(layer "B.CrtYd")
		)
		(fp_poly
			(pts
				(xy -0.5 0.25) (xy -0.5 -0.25) (xy 0.5 -0.25) (xy 0.5 0.25)
			)
			(stroke
				(width 0.15)
				(type solid)
			)
			(fill no)
			(layer "B.Fab")
		)
		(fp_text user "Author: Antmicro"
			(at -0.95 -4.169 0)
			(layer "B.Fab")
			(effects
				(font
					(size 0.7 0.7)
					(thickness 0.15)
				)
				(justify left bottom mirror)
			)
		)
		(fp_text user "${REFERENCE}"
			(at -0.95 -3.168 0)
			(layer "B.Fab")
			(effects
				(font
					(size 0.7 0.7)
					(thickness 0.15)
				)
				(justify left bottom mirror)
			)
		)
		(fp_text user "License: Apache-2.0"
			(at -0.949999 -5.169 0)
			(layer "B.Fab")
			(effects
				(font
					(size 0.7 0.7)
					(thickness 0.15)
				)
				(justify left bottom mirror)
			)
		)
		(pad "1" smd roundrect
			(at -0.48 0 180)
			(size 0.59 0.64)
			(layers "B.Cu" "B.Mask" "B.Paste")
			(roundrect_rratio 0.25)
			(net 1 "GND")
			(pintype "passive")
		)
		(pad "2" smd roundrect
			(at 0.48 0 180)
			(size 0.59 0.64)
			(layers "B.Cu" "B.Mask" "B.Paste")
			(roundrect_rratio 0.25)
			(net 909 "/USB Hub/USBC3_ISET")
			(pintype "passive")
		)
	)
)
